FILE_TYPE=LIBRARY_PARTS;
primitive 'TTL1G86','TTL1G86_SOT','TTL1G86_SOTLF';
  pin
    'A':
      PIN_NUMBER='(1)';
      INPUT_LOAD='(-0.01,0.01)';
    'B':
      PIN_NUMBER='(2)';
      INPUT_LOAD='(-0.01,0.01)';
    'Y':
      PIN_NUMBER='(4)';
      OUTPUT_LOAD='(1.0,-1.0)';
  end_pin;
  body
    POWER_PINS='(VCC:5)';
    POWER_PINS='(GND:3)';
    CLASS='IC';
    PART_NAME='TTL1G86';
    PHYS_DES_PREFIX='U';
  end_body;
end_primitive;
END.
